# SCM (Grand Teton) — schematic netlist excerpt (pin names and nets, part order shuffled) for the footprints in the layout excerpt that follows; sources: Cadence DE-HDL packaged netlist, KiCad conversion of 12092022_DA0F0TMDCD0_F0T_Management_Board_D_brd_V3_OCP.brd

C261  Q_CAP  0.1UF 25V 10% X7R  pkg 0402  page 41 : A = VCCIO0 ; B = GND
R720  Q_RES  0 5% CHIP  pkg 0402LF  page 28 : A = FM_CPU_MSMI_CATERR_LVT3_N ; B = FM_CPU_MSMI_CATERR_LVT3_R3_N

(kicad_pcb
	(version 20260206)
	(generator "pcbnew")
	(generator_version "10.0")
	(general
		(thickness 1.6)
		(legacy_teardrops no)
	)
	(paper "A4")
	(title_block
		(title "12092022_DA0F0TMDCD0_F0T_Management_Board_D_brd_V3_OCP.brd")
		(comment 1 "Grand Teton / footprints 1297-1298 of 1440")
	)
	(layers
		(0 "F.Cu" signal "TOP")
		(4 "In1.Cu" signal "GND")
		(6 "In2.Cu" signal "IN1")
		(8 "In3.Cu" signal "GND1")
		(10 "In4.Cu" signal "IN2")
		(12 "In5.Cu" signal "VCC")
		(14 "In6.Cu" signal "VCC1")
		(16 "In7.Cu" signal "IN3")
		(18 "In8.Cu" signal "GND2")
		(20 "In9.Cu" signal "IN4")
		(22 "In10.Cu" signal "GND3")
		(2 "B.Cu" signal "BOTTOM")
		(9 "F.Adhes" user "F.Adhesive")
		(11 "B.Adhes" user "B.Adhesive")
		(13 "F.Paste" user "Package Geometry/Pastemask Top")
		(15 "B.Paste" user "Package Geometry/Pastemask Bottom")
		(5 "F.SilkS" user "Ref Des/Silkscreen Top")
		(7 "B.SilkS" user "Ref Des/Silkscreen Bottom")
		(1 "F.Mask" user "Board Geometry/Soldermask Top")
		(3 "B.Mask" user "Board Geometry/Soldermask Bottom")
		(17 "Dwgs.User" user "User.Drawings")
		(19 "Cmts.User" user "User.Comments")
		(21 "Eco1.User" user "User.Eco1")
		(23 "Eco2.User" user "User.Eco2")
		(25 "Edge.Cuts" user "Board Geometry/Outline")
		(27 "Margin" user)
		(31 "F.CrtYd" user "Package Geometry/Place Bound Top")
		(29 "B.CrtYd" user "Package Geometry/Place Bound Bottom")
		(35 "F.Fab" user "Ref Des/Assembly Top")
		(33 "B.Fab" user "Ref Des/Assembly Bottom")
	)
	(footprint ""
		(layer "B.Cu")
		(at 51.2445 -89.5985 180)
		(property "Reference" "R720"
			(at 0 0 0)
			(layer "B.SilkS")
			(hide yes)
			(effects
				(font
					(size 1.27 1.27)
				)
				(justify mirror)
			)
		)
		(property "Value" ""
			(at 0 0 0)
			(layer "B.Fab")
			(effects
				(font
					(size 1.27 1.27)
				)
				(justify mirror)
			)
		)
		(duplicate_pad_numbers_are_jumpers no)
		(fp_line
			(start 0.7874 0.4064)
			(end 0.7874 -0.4064)
			(stroke
				(width 0.1524)
				(type default)
			)
			(layer "B.SilkS")
		)
		(fp_line
			(start 0.7874 -0.4064)
			(end -0.7874 -0.4064)
			(stroke
				(width 0.1524)
				(type default)
			)
			(layer "B.SilkS")
		)
		(fp_line
			(start -0.7874 0.4064)
			(end 0.7874 0.4064)
			(stroke
				(width 0.1524)
				(type default)
			)
			(layer "B.SilkS")
		)
		(fp_line
			(start -0.7874 -0.4064)
			(end -0.7874 0.4064)
			(stroke
				(width 0.1524)
				(type default)
			)
			(layer "B.SilkS")
		)
		(fp_line
			(start 0.67945 0.3048)
			(end 0.67945 -0.305054)
			(stroke
				(width 0.1)
				(type default)
			)
			(layer "B.Fab")
		)
		(fp_line
			(start 0.67945 -0.305054)
			(end 0.12065 -0.305054)
			(stroke
				(width 0.1)
				(type default)
			)
			(layer "B.Fab")
		)
		(fp_line
			(start 0.12065 0.3048)
			(end 0.67945 0.3048)
			(stroke
				(width 0.1)
				(type default)
			)
			(layer "B.Fab")
		)
		(fp_line
			(start 0.12065 0.2794)
			(end 0.12065 0.3048)
			(stroke
				(width 0.1)
				(type default)
			)
			(layer "B.Fab")
		)
		(fp_line
			(start 0.12065 -0.2794)
			(end -0.12065 -0.2794)
			(stroke
				(width 0.1)
				(type default)
			)
			(layer "B.Fab")
		)
		(fp_line
			(start 0.12065 -0.305054)
			(end 0.12065 -0.2794)
			(stroke
				(width 0.1)
				(type default)
			)
			(layer "B.Fab")
		)
		(fp_line
			(start -0.120396 0.3048)
			(end -0.120396 0.2794)
			(stroke
				(width 0.1)
				(type default)
			)
			(layer "B.Fab")
		)
		(fp_line
			(start -0.120396 0.2794)
			(end 0.12065 0.2794)
			(stroke
				(width 0.1)
				(type default)
			)
			(layer "B.Fab")
		)
		(fp_line
			(start -0.12065 -0.2794)
			(end -0.12065 -0.3048)
			(stroke
				(width 0.1)
				(type default)
			)
			(layer "B.Fab")
		)
		(fp_line
			(start -0.12065 -0.3048)
			(end -0.67945 -0.3048)
			(stroke
				(width 0.1)
				(type default)
			)
			(layer "B.Fab")
		)
		(fp_line
			(start -0.67945 0.3048)
			(end -0.120396 0.3048)
			(stroke
				(width 0.1)
				(type default)
			)
			(layer "B.Fab")
		)
		(fp_line
			(start -0.67945 -0.3048)
			(end -0.67945 0.3048)
			(stroke
				(width 0.1)
				(type default)
			)
			(layer "B.Fab")
		)
		(pad "1" smd circle
			(at 0.40005 0)
			(size 0 0)
			(layers "B.Cu" "B.Mask" "B.Paste")
			(net "FM_CPU_MSMI_CATERR_LVT3_N")
		)
		(pad "2" smd circle
			(at -0.40005 0)
			(size 0 0)
			(layers "B.Cu" "B.Mask" "B.Paste")
			(net "FM_CPU_MSMI_CATERR_LVT3_R3_N")
		)
	)
	(footprint ""
		(layer "B.Cu")
		(at 25.459436 -89.18702 180)
		(property "Reference" "C261"
			(at 0 0 0)
			(layer "B.SilkS")
			(hide yes)
			(effects
				(font
					(size 1.27 1.27)
				)
				(justify mirror)
			)
		)
		(property "Value" ""
			(at 0 0 0)
			(layer "B.Fab")
			(effects
				(font
					(size 1.27 1.27)
				)
				(justify mirror)
			)
		)
		(duplicate_pad_numbers_are_jumpers no)
		(fp_line
			(start 0.69215 0.2921)
			(end 0.69215 -0.2921)
			(stroke
				(width 0.1524)
				(type default)
			)
			(layer "B.SilkS")
		)
		(fp_line
			(start 0.69215 -0.2921)
			(end -0.69215 -0.2921)
			(stroke
				(width 0.1524)
				(type default)
			)
			(layer "B.SilkS")
		)
		(fp_line
			(start -0.69215 0.2921)
			(end 0.69215 0.2921)
			(stroke
				(width 0.1524)
				(type default)
			)
			(layer "B.SilkS")
		)
		(fp_line
			(start -0.69215 -0.2921)
			(end -0.69215 0.2921)
			(stroke
				(width 0.1524)
				(type default)
			)
			(layer "B.SilkS")
		)
		(fp_line
			(start 0.51435 0.2794)
			(end 0.51435 -0.2794)
			(stroke
				(width 0.1)
				(type default)
			)
			(layer "B.Fab")
		)
		(fp_line
			(start 0.51435 -0.2794)
			(end -0.51435 -0.2794)
			(stroke
				(width 0.1)
				(type default)
			)
			(layer "B.Fab")
		)
		(fp_line
			(start -0.51435 0.2794)
			(end 0.51435 0.2794)
			(stroke
				(width 0.1)
				(type default)
			)
			(layer "B.Fab")
		)
		(fp_line
			(start -0.51435 -0.2794)
			(end -0.51435 0.2794)
			(stroke
				(width 0.1)
				(type default)
			)
			(layer "B.Fab")
		)
		(pad "1" smd circle
			(at 0.40005 0)
			(size 0 0)
			(layers "B.Cu" "B.Mask" "B.Paste")
			(net "VCCIO0")
		)
		(pad "2" smd circle
			(at -0.40005 0)
			(size 0 0)
			(layers "B.Cu" "B.Mask" "B.Paste")
			(net "GND")
		)
		(zone
			(layer "B.Cu")
			(hatch none 0.5)
			(connect_pads
				(clearance 0)
			)
			(min_thickness 0.25)
			(keepout
				(tracks not_allowed)
				(vias allowed)
				(pads allowed)
				(copperpour not_allowed)
				(footprints allowed)
			)
			(placement
				(enabled no)
				(sheetname "")
			)
			(fill
				(thermal_gap 0.5)
				(thermal_bridge_width 0.5)
				(island_removal_mode 0)
			)
			(polygon
				(pts
					(xy 25.268936 -89.27465) (xy 25.360376 -89.332816) (xy 25.559766 -89.332816) (xy 25.649936 -89.27465)
					(xy 25.649936 -89.09939) (xy 25.559766 -89.04097) (xy 25.360376 -89.04097) (xy 25.268936 -89.099136)
				)
			)
		)
	)
)
